(kicad_pcb
	(version 20241229)
	(generator "pcbnew")
	(generator_version "9.0")
	(general
		(thickness 1.61)
		(legacy_teardrops no)
	)
	(paper "A3")
	(title_block
		(title "SO-DIMM DDR5 Tester")
		(date "2025-11-26")
		(rev "1.3.0")
		(comment 9 "footprint 59 of 627 (U4), pads 144-215 of 676")
	)
	(layers
		(0 "F.Cu" signal)
		(4 "In1.Cu" power)
		(6 "In2.Cu" mixed)
		(8 "In3.Cu" power)
		(10 "In4.Cu" mixed)
		(12 "In5.Cu" power)
		(14 "In6.Cu" mixed)
		(16 "In7.Cu" power)
		(18 "In8.Cu" power)
		(20 "In9.Cu" mixed)
		(22 "In10.Cu" power)
		(2 "B.Cu" signal)
		(9 "F.Adhes" user "F.Adhesive")
		(11 "B.Adhes" user "B.Adhesive")
		(13 "F.Paste" user)
		(15 "B.Paste" user)
		(5 "F.SilkS" user "F.Silkscreen")
		(7 "B.SilkS" user "B.Silkscreen")
		(1 "F.Mask" user)
		(3 "B.Mask" user)
		(17 "Dwgs.User" user "User.Drawings")
		(19 "Cmts.User" user "User.Comments")
		(21 "Eco1.User" user "User.Eco1")
		(23 "Eco2.User" user "User.Eco2")
		(25 "Edge.Cuts" user)
		(27 "Margin" user)
		(31 "F.CrtYd" user "F.Courtyard")
		(29 "B.CrtYd" user "B.Courtyard")
		(35 "F.Fab" user)
		(33 "B.Fab" user)
	)
	(footprint "antmicro-footprints:BGA-676_27x27mm_Layout26x26_P1x1mm_FFG676"
		(layer "F.Cu")
		(at 138.875501 174.801 180)
		(descr "FPGA XC7K160TFBG676")
		(tags "FPGA XC7K160TFBG676")
		(property "Reference" "U4"
			(at -12.224499 14.051 180)
			(layer "F.SilkS")
			(effects
				(font
					(size 0.7 0.7)
					(thickness 0.15)
				)
				(justify left bottom)
			)
		)
		(property "Value" "XC7K160T-FFG676"
			(at 0 15.5 180)
			(layer "F.Fab")
			(effects
				(font
					(size 0.7 0.7)
					(thickness 0.15)
				)
				(justify left bottom)
			)
		)
		(property "Datasheet" "https://docs.xilinx.com/v/u/en-US/ds180_7Series_Overview"
			(at 0 0 180)
			(layer "F.Fab")
			(hide yes)
			(effects
				(font
					(size 1.27 1.27)
					(thickness 0.15)
				)
			)
		)
		(property "Author" "Antmicro"
			(at 277.751002 349.602 0)
			(layer "F.Fab")
			(hide yes)
			(effects
				(font
					(size 1 1)
					(thickness 0.15)
				)
			)
		)
		(property "License" "Apache-2.0"
			(at 277.751002 349.602 0)
			(layer "F.Fab")
			(hide yes)
			(effects
				(font
					(size 1 1)
					(thickness 0.15)
				)
			)
		)
		(property "MPN" "XC7K160T-FFG676"
			(at 277.751002 349.602 0)
			(layer "F.Fab")
			(hide yes)
			(effects
				(font
					(size 1 1)
					(thickness 0.15)
				)
			)
		)
		(property "Manufacturer" "AMD-Xilinx"
			(at 277.751002 349.602 0)
			(layer "F.Fab")
			(hide yes)
			(effects
				(font
					(size 1 1)
					(thickness 0.15)
				)
			)
		)
		(sheetname "/FPGA Config/")
		(sheetfile "fpga-config.kicad_sch")
		(attr smd)
		(pad "AE14" smd circle
			(at 0.499 11.499 180)
			(size 0.5 0.5)
			(layers "F.Cu" "F.Mask" "F.Paste")
			(net 1 "GND")
			(pinfunction "GND")
			(pintype "passive")
		)
		(pad "AE15" smd circle
			(at 1.499 11.499 180)
			(size 0.5 0.5)
			(layers "F.Cu" "F.Mask" "F.Paste")
			(net 111 "/DDR5 SODIMM/A.DQ29")
			(pinfunction "IO_L4N_T0_32")
			(pintype "bidirectional")
			(die_length 20.349)
		)
		(pad "AE16" smd circle
			(at 2.499 11.499 180)
			(size 0.5 0.5)
			(layers "F.Cu" "F.Mask" "F.Paste")
			(net 10 "/FPGA banks HP/VREF")
			(pinfunction "IO_L6N_T0_VREF_32")
			(pintype "bidirectional")
			(die_length 18.914)
		)
		(pad "AE17" smd circle
			(at 3.499 11.499 180)
			(size 0.5 0.5)
			(layers "F.Cu" "F.Mask" "F.Paste")
			(net 105 "/DDR5 SODIMM/A.DQ27")
			(pinfunction "IO_L1P_T0_32")
			(pintype "bidirectional")
			(die_length 25.66)
		)
		(pad "AE18" smd circle
			(at 4.499 11.499 180)
			(size 0.5 0.5)
			(layers "F.Cu" "F.Mask" "F.Paste")
			(net 108 "/DDR5 SODIMM/A.DQS3_P")
			(pinfunction "IO_L3P_T0_DQS_32")
			(pintype "bidirectional")
			(die_length 23.868)
		)
		(pad "AE19" smd circle
			(at 5.499 11.499 180)
			(size 0.5 0.5)
			(layers "F.Cu" "F.Mask" "F.Paste")
			(net 206 "+1V1")
			(pinfunction "VCCO_32")
			(pintype "passive")
		)
		(pad "AE20" smd circle
			(at 6.499 11.499 180)
			(size 0.5 0.5)
			(layers "F.Cu" "F.Mask" "F.Paste")
			(net 81 "/DDR5 SODIMM/A.DQS1_N")
			(pinfunction "IO_L15N_T2_DQS_32")
			(pintype "bidirectional")
			(die_length 21.92)
		)
		(pad "AE21" smd circle
			(at 7.499 11.499 180)
			(size 0.5 0.5)
			(layers "F.Cu" "F.Mask" "F.Paste")
			(net 249 "TB_DETECT")
			(pinfunction "IO_L19N_T3_VREF_12")
			(pintype "bidirectional")
			(die_length 13.224)
		)
		(pad "AE22" smd circle
			(at 8.499 11.499 180)
			(size 0.5 0.5)
			(layers "F.Cu" "F.Mask" "F.Paste")
			(net 699 "/FPGA bank 12/HyperRAM.DQ3")
			(pinfunction "IO_L24P_T3_12")
			(pintype "bidirectional")
			(die_length 13.617)
		)
		(pad "AE23" smd circle
			(at 9.499 11.499 180)
			(size 0.5 0.5)
			(layers "F.Cu" "F.Mask" "F.Paste")
			(net 698 "/FPGA bank 12/HyperRAM.DQ0")
			(pinfunction "IO_L22P_T3_12")
			(pintype "bidirectional")
			(die_length 17.11)
		)
		(pad "AE24" smd circle
			(at 10.499 11.499 180)
			(size 0.5 0.5)
			(layers "F.Cu" "F.Mask" "F.Paste")
			(net 1 "GND")
			(pinfunction "GND")
			(pintype "passive")
		)
		(pad "AE25" smd circle
			(at 11.499 11.499 180)
			(size 0.5 0.5)
			(layers "F.Cu" "F.Mask" "F.Paste")
			(net 702 "/FPGA bank 12/HyperRAM.DQ6")
			(pinfunction "IO_L23N_T3_12")
			(pintype "bidirectional")
			(die_length 16.458)
		)
		(pad "AE26" smd circle
			(at 12.499 11.499 180)
			(size 0.5 0.5)
			(layers "F.Cu" "F.Mask" "F.Paste")
			(net 693 "/FPGA bank 12/HyperRAM.CK_N")
			(pinfunction "IO_L21N_T3_DQS_12")
			(pintype "bidirectional")
			(die_length 17.907)
		)
		(pad "AF1" smd circle
			(at -12.5 12.499 180)
			(size 0.5 0.5)
			(layers "F.Cu" "F.Mask" "F.Paste")
			(net 1 "GND")
			(pinfunction "GND")
			(pintype "passive")
		)
		(pad "AF2" smd circle
			(at -11.5 12.499 180)
			(size 0.5 0.5)
			(layers "F.Cu" "F.Mask" "F.Paste")
			(net 205 "/DDR5 SODIMM/B.DQ4")
			(pinfunction "IO_L24N_T3_34")
			(pintype "bidirectional")
			(die_length 24.825)
		)
		(pad "AF3" smd circle
			(at -10.5 12.499 180)
			(size 0.5 0.5)
			(layers "F.Cu" "F.Mask" "F.Paste")
			(net 197 "/DDR5 SODIMM/B.DQ2")
			(pinfunction "IO_L24P_T3_34")
			(pintype "bidirectional")
			(die_length 23.875)
		)
		(pad "AF4" smd circle
			(at -9.5 12.499 180)
			(size 0.5 0.5)
			(layers "F.Cu" "F.Mask" "F.Paste")
			(net 203 "/DDR5 SODIMM/B.DQS0_N")
			(pinfunction "IO_L21N_T3_DQS_34")
			(pintype "bidirectional")
			(die_length 21.687)
		)
		(pad "AF5" smd circle
			(at -8.5 12.499 180)
			(size 0.5 0.5)
			(layers "F.Cu" "F.Mask" "F.Paste")
			(net 204 "/DDR5 SODIMM/B.DQS0_P")
			(pinfunction "IO_L21P_T3_DQS_34")
			(pintype "bidirectional")
			(die_length 22.107)
		)
		(pad "AF6" smd circle
			(at -7.5 12.499 180)
			(size 0.5 0.5)
			(layers "F.Cu" "F.Mask" "F.Paste")
			(net 206 "+1V1")
			(pinfunction "VCCO_34")
			(pintype "passive")
		)
		(pad "AF7" smd circle
			(at -6.5 12.499 180)
			(size 0.5 0.5)
			(layers "F.Cu" "F.Mask" "F.Paste")
			(net 190 "/DDR5 SODIMM/B.DQS4_N")
			(pinfunction "IO_L7N_T1_33")
			(pintype "bidirectional")
			(die_length 18.816)
		)
		(pad "AF8" smd circle
			(at -5.5 12.499 180)
			(size 0.5 0.5)
			(layers "F.Cu" "F.Mask" "F.Paste")
			(net 117 "/DDR5 SODIMM/A.DQS4_N")
			(pinfunction "IO_L22N_T3_33")
			(pintype "bidirectional")
			(die_length 19.356)
		)
		(pad "AF9" smd circle
			(at -4.5 12.499 180)
			(size 0.5 0.5)
			(layers "F.Cu" "F.Mask" "F.Paste")
			(net 182 "/DDR5 SODIMM/Control.~{RESET}")
			(pinfunction "IO_L24N_T3_33")
			(pintype "bidirectional")
			(die_length 18.041)
		)
		(pad "AF10" smd circle
			(at -3.5 12.499 180)
			(size 0.5 0.5)
			(layers "F.Cu" "F.Mask" "F.Paste")
			(net 184 "/DDR5 SODIMM/B.~{CS1}")
			(pinfunction "IO_L24P_T3_33")
			(pintype "bidirectional")
			(die_length 18.552)
		)
		(pad "AF11" smd circle
			(at -2.5 12.499 180)
			(size 0.5 0.5)
			(layers "F.Cu" "F.Mask" "F.Paste")
			(net 1 "GND")
			(pinfunction "GND")
			(pintype "passive")
		)
		(pad "AF12" smd circle
			(at -1.5 12.499 180)
			(size 0.5 0.5)
			(layers "F.Cu" "F.Mask" "F.Paste")
			(net 160 "/DDR5 SODIMM/A.CK1_N")
			(pinfunction "IO_L21N_T3_DQS_33")
			(pintype "bidirectional")
			(die_length 18.818)
		)
		(pad "AF13" smd circle
			(at -0.5 12.499 180)
			(size 0.5 0.5)
			(layers "F.Cu" "F.Mask" "F.Paste")
			(net 164 "/DDR5 SODIMM/B.CK1_N")
			(pinfunction "IO_L23N_T3_33")
			(pintype "bidirectional")
			(die_length 20.747)
		)
		(pad "AF14" smd circle
			(at 0.499 12.499 180)
			(size 0.5 0.5)
			(layers "F.Cu" "F.Mask" "F.Paste")
			(net 113 "/DDR5 SODIMM/A.DQ31")
			(pinfunction "IO_L2P_T0_32")
			(pintype "bidirectional")
			(die_length 20.408)
		)
		(pad "AF15" smd circle
			(at 1.499 12.499 180)
			(size 0.5 0.5)
			(layers "F.Cu" "F.Mask" "F.Paste")
			(net 112 "/DDR5 SODIMM/A.DQ30")
			(pinfunction "IO_L2N_T0_32")
			(pintype "bidirectional")
			(die_length 21.691)
		)
		(pad "AF16" smd circle
			(at 2.499 12.499 180)
			(size 0.5 0.5)
			(layers "F.Cu" "F.Mask" "F.Paste")
			(net 206 "+1V1")
			(pinfunction "VCCO_32")
			(pintype "passive")
		)
		(pad "AF17" smd circle
			(at 3.499 12.499 180)
			(size 0.5 0.5)
			(layers "F.Cu" "F.Mask" "F.Paste")
			(net 109 "/DDR5 SODIMM/A.~{DM3}")
			(pinfunction "IO_L1N_T0_32")
			(pintype "bidirectional")
			(die_length 25.392)
		)
		(pad "AF18" smd circle
			(at 4.499 12.499 180)
			(size 0.5 0.5)
			(layers "F.Cu" "F.Mask" "F.Paste")
			(net 107 "/DDR5 SODIMM/A.DQS3_N")
			(pinfunction "IO_L3N_T0_DQS_32")
			(pintype "bidirectional")
			(die_length 23.477)
		)
		(pad "AF19" smd circle
			(at 5.499 12.499 180)
			(size 0.5 0.5)
			(layers "F.Cu" "F.Mask" "F.Paste")
			(net 104 "/DDR5 SODIMM/A.DQ26")
			(pinfunction "IO_L5P_T0_32")
			(pintype "bidirectional")
			(die_length 22.609)
		)
		(pad "AF20" smd circle
			(at 6.499 12.499 180)
			(size 0.5 0.5)
			(layers "F.Cu" "F.Mask" "F.Paste")
			(net 102 "/DDR5 SODIMM/A.DQ24")
			(pinfunction "IO_L5N_T0_32")
			(pintype "bidirectional")
			(die_length 22.255)
		)
		(pad "AF21" smd circle
			(at 7.499 12.499 180)
			(size 0.5 0.5)
			(layers "F.Cu" "F.Mask" "F.Paste")
			(net 1 "GND")
			(pinfunction "GND")
			(pintype "passive")
		)
		(pad "AF22" smd circle
			(at 8.499 12.499 180)
			(size 0.5 0.5)
			(layers "F.Cu" "F.Mask" "F.Paste")
			(net 248 "~{DDR_PRESENCE}")
			(pinfunction "IO_L24N_T3_12")
			(pintype "bidirectional")
			(die_length 14.462)
		)
		(pad "AF23" smd circle
			(at 9.499 12.499 180)
			(size 0.5 0.5)
			(layers "F.Cu" "F.Mask" "F.Paste")
			(net 700 "/FPGA bank 12/HyperRAM.DQ4")
			(pinfunction "IO_L22N_T3_12")
			(pintype "bidirectional")
			(die_length 16.26)
		)
		(pad "AF24" smd circle
			(at 10.499 12.499 180)
			(size 0.5 0.5)
			(layers "F.Cu" "F.Mask" "F.Paste")
			(net 696 "/FPGA bank 12/HyperRAM.DQ2")
			(pinfunction "IO_L20P_T3_12")
			(pintype "bidirectional")
			(die_length 17.799)
		)
		(pad "AF25" smd circle
			(at 11.499 12.499 180)
			(size 0.5 0.5)
			(layers "F.Cu" "F.Mask" "F.Paste")
			(net 703 "/FPGA bank 12/HyperRAM.DQ5")
			(pinfunction "IO_L20N_T3_12")
			(pintype "bidirectional")
			(die_length 18.603)
		)
		(pad "AF26" smd circle
			(at 12.499 12.499 180)
			(size 0.5 0.5)
			(layers "F.Cu" "F.Mask" "F.Paste")
			(net 200 "+3V3")
			(pinfunction "VCCO_12")
			(pintype "passive")
		)
		(pad "B1" smd circle
			(at -12.5 -11.5 180)
			(size 0.5 0.5)
			(layers "F.Cu" "F.Mask" "F.Paste")
			(net 30 "/FPGA MGT Interface/GTX_TX2_N")
			(pinfunction "MGTXTXN2_116")
			(pintype "bidirectional")
			(die_length 15.86)
		)
		(pad "B2" smd circle
			(at -11.5 -11.5 180)
			(size 0.5 0.5)
			(layers "F.Cu" "F.Mask" "F.Paste")
			(net 21 "/FPGA MGT Interface/GTX_TX2_P")
			(pinfunction "MGTXTXP2_116")
			(pintype "bidirectional")
			(die_length 16.008)
		)
		(pad "B3" smd circle
			(at -10.5 -11.5 180)
			(size 0.5 0.5)
			(layers "F.Cu" "F.Mask" "F.Paste")
			(net 226 "+1V2_MGTAVTT")
			(pinfunction "MGTAVTT")
			(pintype "power_in")
		)
		(pad "B4" smd circle
			(at -9.5 -11.5 180)
			(size 0.5 0.5)
			(layers "F.Cu" "F.Mask" "F.Paste")
			(net 1 "GND")
			(pinfunction "GND")
			(pintype "passive")
		)
		(pad "B5" smd circle
			(at -8.5 -11.5 180)
			(size 0.5 0.5)
			(layers "F.Cu" "F.Mask" "F.Paste")
			(net 605 "/FPGA MGT Interface/PCIE.RXD0_N")
			(pinfunction "MGTXRXN3_116")
			(pintype "bidirectional")
			(die_length 13.646)
		)
		(pad "B6" smd circle
			(at -7.5 -11.5 180)
			(size 0.5 0.5)
			(layers "F.Cu" "F.Mask" "F.Paste")
			(net 604 "/FPGA MGT Interface/PCIE.RXD0_P")
			(pinfunction "MGTXRXP3_116")
			(pintype "bidirectional")
			(die_length 13.747)
		)
		(pad "B7" smd circle
			(at -6.5 -11.5 180)
			(size 0.5 0.5)
			(layers "F.Cu" "F.Mask" "F.Paste")
			(net 1 "GND")
			(pinfunction "GND")
			(pintype "passive")
		)
		(pad "B8" smd circle
			(at -5.5 -11.5 180)
			(size 0.5 0.5)
			(layers "F.Cu" "F.Mask" "F.Paste")
			(net 200 "+3V3")
			(pinfunction "VCCO_16")
			(pintype "passive")
		)
		(pad "B9" smd circle
			(at -4.5 -11.5 180)
			(size 0.5 0.5)
			(layers "F.Cu" "F.Mask" "F.Paste")
			(net 401 "unconnected-(U4E-IO_L10N_T1_16-PadB9)")
			(pinfunction "IO_L10N_T1_16")
			(pintype "bidirectional+no_connect")
			(die_length 21.661)
		)
		(pad "B10" smd circle
			(at -3.5 -11.5 180)
			(size 0.5 0.5)
			(layers "F.Cu" "F.Mask" "F.Paste")
			(net 660 "/FPGA bank 16/HDMI.D2_P")
			(pinfunction "IO_L22P_T3_16")
			(pintype "bidirectional")
			(die_length 19.148)
		)
		(pad "B11" smd circle
			(at -2.5 -11.5 180)
			(size 0.5 0.5)
			(layers "F.Cu" "F.Mask" "F.Paste")
			(net 402 "unconnected-(U4E-IO_L20N_T3_16-PadB11)")
			(pinfunction "IO_L20N_T3_16")
			(pintype "bidirectional+no_connect")
			(die_length 19.129)
		)
		(pad "B12" smd circle
			(at -1.5 -11.5 180)
			(size 0.5 0.5)
			(layers "F.Cu" "F.Mask" "F.Paste")
			(net 403 "unconnected-(U4E-IO_L20P_T3_16-PadB12)")
			(pinfunction "IO_L20P_T3_16")
			(pintype "bidirectional+no_connect")
			(die_length 19.084)
		)
		(pad "B13" smd circle
			(at -0.5 -11.5 180)
			(size 0.5 0.5)
			(layers "F.Cu" "F.Mask" "F.Paste")
			(net 1 "GND")
			(pinfunction "GND")
			(pintype "passive")
		)
		(pad "B14" smd circle
			(at 0.499 -11.5 180)
			(size 0.5 0.5)
			(layers "F.Cu" "F.Mask" "F.Paste")
			(net 664 "/FPGA bank 16/HDMI.D0_P")
			(pinfunction "IO_L21P_T3_DQS_16")
			(pintype "bidirectional")
			(die_length 17.698)
		)
		(pad "B15" smd circle
			(at 1.499 -11.5 180)
			(size 0.5 0.5)
			(layers "F.Cu" "F.Mask" "F.Paste")
			(net 666 "/FPGA bank 16/HDMI.CLK_P")
			(pinfunction "IO_L23P_T3_16")
			(pintype "bidirectional")
			(die_length 17.518)
		)
		(pad "B16" smd circle
			(at 2.499 -11.5 180)
			(size 0.5 0.5)
			(layers "F.Cu" "F.Mask" "F.Paste")
			(net 404 "unconnected-(U4D-IO_L1N_T0_AD0N_15-PadB16)")
			(pinfunction "IO_L1N_T0_AD0N_15")
			(pintype "bidirectional+no_connect")
			(die_length 16.625)
		)
		(pad "B17" smd circle
			(at 3.499 -11.5 180)
			(size 0.5 0.5)
			(layers "F.Cu" "F.Mask" "F.Paste")
			(net 405 "unconnected-(U4D-IO_L3P_T0_DQS_AD1P_15-PadB17)")
			(pinfunction "IO_L3P_T0_DQS_AD1P_15")
			(pintype "bidirectional+no_connect")
			(die_length 17.668)
		)
		(pad "B18" smd circle
			(at 4.499 -11.5 180)
			(size 0.5 0.5)
			(layers "F.Cu" "F.Mask" "F.Paste")
			(net 377 "Net-(R97-Pad2)")
			(pinfunction "VCCO_15")
			(pintype "power_in")
		)
		(pad "B19" smd circle
			(at 5.499 -11.5 180)
			(size 0.5 0.5)
			(layers "F.Cu" "F.Mask" "F.Paste")
			(net 406 "unconnected-(U4D-IO_L4N_T0_AD9N_15-PadB19)")
			(pinfunction "IO_L4N_T0_AD9N_15")
			(pintype "bidirectional+no_connect")
			(die_length 18.77)
		)
		(pad "B20" smd circle
			(at 6.499 -11.5 180)
			(size 0.5 0.5)
			(layers "F.Cu" "F.Mask" "F.Paste")
			(net 619 "/FPGA bank 14/USR_LED2")
			(pinfunction "IO_L8P_T1_D11_14")
			(pintype "bidirectional")
			(die_length 20.881)
		)
		(pad "B21" smd circle
			(at 7.499 -11.5 180)
			(size 0.5 0.5)
			(layers "F.Cu" "F.Mask" "F.Paste")
			(net 617 "/FPGA bank 14/USR_LED3")
			(pinfunction "IO_L10N_T1_D15_14")
			(pintype "bidirectional")
			(die_length 22.228)
		)
		(pad "B22" smd circle
			(at 8.499 -11.5 180)
			(size 0.5 0.5)
			(layers "F.Cu" "F.Mask" "F.Paste")
			(net 628 "/FPGA Config/FLASH.IO2")
			(pinfunction "IO_L2P_T0_D02_14")
			(pintype "bidirectional")
			(die_length 20.4)
		)
		(pad "B23" smd circle
			(at 9.499 -11.5 180)
			(size 0.5 0.5)
			(layers "F.Cu" "F.Mask" "F.Paste")
			(net 1 "GND")
			(pinfunction "GND")
			(pintype "passive")
		)
		(pad "B24" smd circle
			(at 10.499 -11.5 180)
			(size 0.5 0.5)
			(layers "F.Cu" "F.Mask" "F.Paste")
			(net 626 "/FPGA Config/FLASH.IO0")
			(pinfunction "IO_L1P_T0_D00_MOSI_14")
			(pintype "bidirectional")
			(die_length 22.518)
		)
		(pad "B25" smd circle
			(at 11.499 -11.5 180)
			(size 0.5 0.5)
			(layers "F.Cu" "F.Mask" "F.Paste")
			(net 612 "/FPGA bank 14/PUDC_B")
			(pinfunction "IO_L3P_T0_DQS_PUDC_B_14")
			(pintype "bidirectional")
			(die_length 23.894)
		)
		(pad "B26" smd circle
			(at 12.499 -11.5 180)
			(size 0.5 0.5)
			(layers "F.Cu" "F.Mask" "F.Paste")
			(net 44 "/FPGA bank 14/EMCCLK")
			(pinfunction "IO_L3N_T0_DQS_EMCCLK_14")
			(pintype "bidirectional")
			(die_length 24.039)
		)
		(pad "C1" smd circle
			(at -12.5 -10.5 180)
			(size 0.5 0.5)
			(layers "F.Cu" "F.Mask" "F.Paste")
			(net 1 "GND")
			(pinfunction "GND")
			(pintype "passive")
		)
		(pad "C2" smd circle
			(at -11.5 -10.5 180)
			(size 0.5 0.5)
			(layers "F.Cu" "F.Mask" "F.Paste")
			(net 226 "+1V2_MGTAVTT")
			(pinfunction "MGTAVTT")
			(pintype "passive")
		)
		(pad "C3" smd circle
			(at -10.5 -10.5 180)
			(size 0.5 0.5)
			(layers "F.Cu" "F.Mask" "F.Paste")
			(net 607 "/FPGA MGT Interface/PCIE.RXD1_N")
			(pinfunction "MGTXRXN2_116")
			(pintype "bidirectional")
			(die_length 14.495)
		)
		(pad "C4" smd circle
			(at -9.5 -10.5 180)
			(size 0.5 0.5)
			(layers "F.Cu" "F.Mask" "F.Paste")
			(net 606 "/FPGA MGT Interface/PCIE.RXD1_P")
			(pinfunction "MGTXRXP2_116")
			(pintype "bidirectional")
			(die_length 14.581)
		)
		(pad "C5" smd circle
			(at -8.5 -10.5 180)
			(size 0.5 0.5)
			(layers "F.Cu" "F.Mask" "F.Paste")
			(net 1 "GND")
			(pinfunction "GND")
			(pintype "passive")
		)
		(pad "C6" smd circle
			(at -7.5 -10.5 180)
			(size 0.5 0.5)
			(layers "F.Cu" "F.Mask" "F.Paste")
			(net 187 "+1V0_MGTAVCC")
			(pinfunction "MGTAVCC")
			(pintype "power_in")
		)
		(pad "C7" smd circle
			(at -6.5 -10.5 180)
			(size 0.5 0.5)
			(layers "F.Cu" "F.Mask" "F.Paste")
			(net 1 "GND")
			(pinfunction "GND")
			(pintype "passive")
		)
	)
)
